# T6G (Grand Teton) — schematic netlist excerpt (pin names and nets, part order shuffled) for the footprints in the layout excerpt that follows; sources: Cadence DE-HDL packaged netlist, KiCad conversion of 04192023_DAF0TMB3IC0_F0TG_MB_C_brd_V02_OCP.brd

J67  SCONN288_DDR506112002KQ  IO  pkg DDR288S_1-1VXC  page 97
  VIN_BULK0  = P12V_MEM_CPU0
  RFU0  = NC
  VIN_MGMT  = P3V3_AUX
  HSCL  = I3C_SPD_DDRL_CPU0_SCL
  HSDA  = I3C_SPD_DDRL_CPU0_SDA
  VSS0  = GND
  DQ0_A  = M_L_CPU0_SA_DQ<0>
  VSS1  = GND
  DQ1_A  = M_L_CPU0_SA_DQ<1>
  VSS2  = GND
  DQS0_A_T  = M_L_CPU0_SA_DQS_DP<0>
  DQS0_A_C  = M_L_CPU0_SA_DQS_DN<0>
  VSS3  = GND
  DQ4_A  = M_L_CPU0_SA_DQ<4>
  VSS4  = GND
  DQ5_A  = M_L_CPU0_SA_DQ<5>
  VSS5  = GND
  DQ8_A  = M_L_CPU0_SA_DQ<8>
  VSS6  = GND
  DQ9_A  = M_L_CPU0_SA_DQ<9>
  VSS7  = GND
  DQS1_A_T  = M_L_CPU0_SA_DQS_DP<1>
  DQS1_A_C  = M_L_CPU0_SA_DQS_DN<1>
  VSS8  = GND
  DQ12_A  = M_L_CPU0_SA_DQ<12>
  VSS9  = GND
  DQ13_A  = M_L_CPU0_SA_DQ<13>
  VSS10  = GND
  DQ16_A  = M_L_CPU0_SA_DQ<16>
  VSS11  = GND
  DQ17_A  = M_L_CPU0_SA_DQ<17>
  VSS12  = GND
  DQS2_A_T  = M_L_CPU0_SA_DQS_DP<2>
  DQS2_A_C  = M_L_CPU0_SA_DQS_DN<2>
  VSS13  = GND
  DQ20_A  = M_L_CPU0_SA_DQ<20>
  VSS14  = GND
  DQ21_A  = M_L_CPU0_SA_DQ<21>
  VSS15  = GND
  DQ24_A  = M_L_CPU0_SA_DQ<24>
  VSS16  = GND
  DQ25_A  = M_L_CPU0_SA_DQ<25>
  VSS17  = GND
  DQS3_A_T  = M_L_CPU0_SA_DQS_DP<3>
  DQS3_A_C  = M_L_CPU0_SA_DQS_DN<3>
  VSS18  = GND
  DQ28_A  = M_L_CPU0_SA_DQ<28>
  VSS19  = GND
  DQ29_A  = M_L_CPU0_SA_DQ<29>
  VSS20  = GND
  CB0_A  = M_L_CPU0_SA_CB<0>
  VSS21  = GND
  CB1_A  = M_L_CPU0_SA_CB<1>
  VSS22  = GND
  DQS4_A_T  = M_L_CPU0_SA_DQS_DP<4>
  DQS4_A_C  = M_L_CPU0_SA_DQS_DN<4>
  VSS23  = GND
  CB4_A  = M_L_CPU0_SA_CB<4>
  VSS24  = GND
  CB5_A  = M_L_CPU0_SA_CB<5>
  VSS25  = GND
  ALERT_N  = M_L_CPU0_ALERT_N
  VSS26  = GND
  CS0_A_N  = M_L_CPU0_SA_CS_N<0>
  VSS27  = GND
  CA0_A  = M_L_CPU0_SA_CA<0>
  VSS28  = GND
  CA2_A  = M_L_CPU0_SA_CA<2>
  VSS29  = GND
  CA4_A  = M_L_CPU0_SA_CA<4>
  VSS30  = GND
  CA6_A  = M_L_CPU0_SA_CA<6>
  VSS31  = GND
  PAR_A  = M_L_CPU0_SA_PAR
  VSS32  = GND
  CA0_B  = M_L_CPU0_SB_CA<0>
  VSS33  = GND
  CA2_B  = M_L_CPU0_SB_CA<2>
  VSS34  = GND
  CA4_B  = M_L_CPU0_SB_CA<4>
  VSS35  = GND
  CA6_B  = M_L_CPU0_SB_CA<6>
  VSS36  = GND
  CS0_B_N  = M_L_CPU0_SB_CS_N<0>
  VSS37  = GND
  \lbd||rsp_a_n\  = M_L_CPU0_SA_RSP<0>
  \lbs||rsp_b_n\  = M_L_CPU0_SB_RSP<0>
  VSS38  = GND
  CB4_B  = M_L_CPU0_SB_CB<4>
  VSS39  = GND
  CB5_B  = M_L_CPU0_SB_CB<5>
  VSS40  = GND
  \dqs9_b_t||tdqs9_b_t||dbi4_b_n\  = M_L_CPU0_SB_DQS_DP<9>
  \dqs9_b_c||tdqs9_b_c\  = M_L_CPU0_SB_DQS_DN<9>
  VSS41  = GND
  CB0_B  = M_L_CPU0_SB_CB<0>
  VSS42  = GND
  CB1_B  = M_L_CPU0_SB_CB<1>
  VSS43  = GND
  DQ0_B  = M_L_CPU0_SB_DQ<0>
  VSS44  = GND
  DQ1_B  = M_L_CPU0_SB_DQ<1>
  VSS45  = GND
  DQS0_B_T  = M_L_CPU0_SB_DQS_DP<0>
  DQS0_B_C  = M_L_CPU0_SB_DQS_DN<0>
  VSS46  = GND
  DQ4_B  = M_L_CPU0_SB_DQ<4>
  VSS47  = GND
  DQ5_B  = M_L_CPU0_SB_DQ<5>
  VSS48  = GND
  DQ8_B  = M_L_CPU0_SB_DQ<8>
  VSS49  = GND
  DQ9_B  = M_L_CPU0_SB_DQ<9>
  VSS50  = GND
  DQS1_B_T  = M_L_CPU0_SB_DQS_DP<1>
  DQS1_B_C  = M_L_CPU0_SB_DQS_DN<1>
  VSS51  = GND
  DQ12_B  = M_L_CPU0_SB_DQ<12>
  VSS52  = GND
  DQ13_B  = M_L_CPU0_SB_DQ<13>
  VSS53  = GND
  DQ16_B  = M_L_CPU0_SB_DQ<16>
  VSS54  = GND
  DQ17_B  = M_L_CPU0_SB_DQ<17>
  VSS55  = GND
  DQS2_B_T  = M_L_CPU0_SB_DQS_DP<2>
  DQS2_B_C  = M_L_CPU0_SB_DQS_DN<2>
  VSS56  = GND
  DQ20_B  = M_L_CPU0_SB_DQ<20>
  VSS57  = GND
  DQ21_B  = M_L_CPU0_SB_DQ<21>
  VSS58  = GND
  DQ24_B  = M_L_CPU0_SB_DQ<24>
  VSS59  = GND
  DQ25_B  = M_L_CPU0_SB_DQ<25>
  VSS60  = GND
  DQS3_B_T  = M_L_CPU0_SB_DQS_DP<3>
  DQS3_B_C  = M_L_CPU0_SB_DQS_DN<3>
  VSS61  = GND
  DQ28_B  = M_L_CPU0_SB_DQ<28>
  VSS62  = GND
  DQ29_B  = M_L_CPU0_SB_DQ<29>
  VSS63  = GND
  RFU1  = NC
  VIN_BULK1  = P12V_MEM_CPU0
  VIN_BULK2  = P12V_MEM_CPU0
  \pwr_good||fail_n\  = PWRGD_CHL_CPU0_DIMM
  HAS  = PD_CHL_CPU0_DIMM_SAA
  RFU2  = NC
  RFU3  = NC
  VSS64  = GND
  DQ2_A  = M_L_CPU0_SA_DQ<2>
  VSS65  = GND
  DQ3_A  = M_L_CPU0_SA_DQ<3>
  VSS66  = GND
  \dqs5_a_c||tdqs5_a_c||dqs5_a_t||tdqs5_a_t\  = M_L_CPU0_SA_DQS_DN<5>
  \dqs5_a_t||tdqs5_a_t\  = M_L_CPU0_SA_DQS_DP<5>
  VSS67  = GND
  DQ6_A  = M_L_CPU0_SA_DQ<6>
  VSS68  = GND
  DQ7_A  = M_L_CPU0_SA_DQ<7>
  VSS69  = GND
  DQ10_A  = M_L_CPU0_SA_DQ<10>
  VSS70  = GND
  DQ11_A  = M_L_CPU0_SA_DQ<11>
  VSS71  = GND
  \dqs6_a_c||tdqs6_a_c||dqs6_a_t||tdqs6_a_t\  = M_L_CPU0_SA_DQS_DN<6>
  \dqs6_a_t||tdqs6_a_t\  = M_L_CPU0_SA_DQS_DP<6>
  VSS72  = GND
  DQ14_A  = M_L_CPU0_SA_DQ<14>
  VSS73  = GND
  DQ15_A  = M_L_CPU0_SA_DQ<15>
  VSS74  = GND
  DQ18_A  = M_L_CPU0_SA_DQ<18>
  VSS75  = GND
  DQ19_A  = M_L_CPU0_SA_DQ<19>
  VSS76  = GND
  \dqs7_a_c||tdqs7_a_c\  = M_L_CPU0_SA_DQS_DN<7>
  \dqs7_a_t||tdqs7_a_t\  = M_L_CPU0_SA_DQS_DP<7>
  VSS77  = GND
  DQ22_A  = M_L_CPU0_SA_DQ<22>
  VSS78  = GND
  DQ23_A  = M_L_CPU0_SA_DQ<23>
  VSS79  = GND
  DQ26_A  = M_L_CPU0_SA_DQ<26>
  VSS80  = GND
  DQ27_A  = M_L_CPU0_SA_DQ<27>
  VSS81  = GND
  \dqs8_a_c||tdqs8_a_c\  = M_L_CPU0_SA_DQS_DN<8>
  \dqs8_a_t||tdqs8_a_t\  = M_L_CPU0_SA_DQS_DP<8>
  VSS82  = GND
  DQ30_A  = M_L_CPU0_SA_DQ<30>
  VSS83  = GND
  DQ31_A  = M_L_CPU0_SA_DQ<31>
  VSS84  = GND
  CB2_A  = M_L_CPU0_SA_CB<2>
  VSS85  = GND
  CB3_A  = M_L_CPU0_SA_CB<3>
  VSS86  = GND
  \dqs9_a_c||tdqs9_a_c\  = M_L_CPU0_SA_DQS_DN<9>
  \dqs9_a_t||tdqs9_a_t\  = M_L_CPU0_SA_DQS_DP<9>
  VSS87  = GND
  CB6_A  = M_L_CPU0_SA_CB<6>
  VSS88  = GND
  CB7_A  = M_L_CPU0_SA_CB<7>
  VSS89  = GND
  RESET_N  = M_L_CPU0_RESET_N
  VSS90  = GND
  CS1_A_N  = M_L_CPU0_SA_CS_N<1>
  VSS91  = GND
  CA1_A  = M_L_CPU0_SA_CA<1>
  VSS92  = GND
  CA3_A  = M_L_CPU0_SA_CA<3>
  VSS93  = GND
  CA5_A  = M_L_CPU0_SA_CA<5>
  VSS94  = GND
  CK_T  = M_L_CPU0_CLK_DP<0>
  CK_C  = M_L_CPU0_CLK_DN<0>
  VSS95  = GND
  RFU4  = NC
  CA1_B  = M_L_CPU0_SB_CA<1>
  VSS96  = GND
  CA3_B  = M_L_CPU0_SB_CA<3>
  VSS97  = GND
  CA5_B  = M_L_CPU0_SB_CA<5>
  VSS98  = GND
  PAR_B  = M_L_CPU0_SB_PAR
  VSS99  = GND
  CS1_B_N  = M_L_CPU0_SB_CS_N<1>
  VSS100  = GND
  RFU5  = NC
  RFU6  = NC
  VSS101  = GND
  CB6_B  = M_L_CPU0_SB_CB<6>
  VSS102  = GND
  CB7_B  = M_L_CPU0_SB_CB<7>
  VSS103  = GND
  DQS4_B_C  = M_L_CPU0_SB_DQS_DN<4>
  DQS4_B_T  = M_L_CPU0_SB_DQS_DP<4>
  VSS104  = GND
  CB2_B  = M_L_CPU0_SB_CB<2>
  VSS105  = GND
  CB3_B  = M_L_CPU0_SB_CB<3>
  VSS106  = GND
  DQ2_B  = M_L_CPU0_SB_DQ<2>
  VSS107  = GND
  DQ3_B  = M_L_CPU0_SB_DQ<3>
  VSS108  = GND
  \dqs5_b_c||tdqs5_b_c\  = M_L_CPU0_SB_DQS_DN<5>
  \dqs5_b_t||tdqs5_b_t\  = M_L_CPU0_SB_DQS_DP<5>
  VSS109  = GND
  DQ6_B  = M_L_CPU0_SB_DQ<6>
  VSS110  = GND
  DQ7_B  = M_L_CPU0_SB_DQ<7>
  VSS111  = GND
  DQ10_B  = M_L_CPU0_SB_DQ<10>
  VSS112  = GND
  DQ11_B  = M_L_CPU0_SB_DQ<11>
  VSS113  = GND
  \dqs6_b_c||tdqs6_b_c\  = M_L_CPU0_SB_DQS_DN<6>
  \dqs6_b_t||tdqs6_b_t\  = M_L_CPU0_SB_DQS_DP<6>
  VSS114  = GND
  DQ14_B  = M_L_CPU0_SB_DQ<14>
  VSS115  = GND
  DQ15_B  = M_L_CPU0_SB_DQ<15>
  VSS116  = GND
  DQ18_B  = M_L_CPU0_SB_DQ<18>
  VSS117  = GND
  DQ19_B  = M_L_CPU0_SB_DQ<19>
  VSS118  = GND
  \dqs7_b_c||tdqs7_b_c\  = M_L_CPU0_SB_DQS_DN<7>
  \dqs7_b_t||tdqs7_b_t\  = M_L_CPU0_SB_DQS_DP<7>
  VSS119  = GND
  DQ22_B  = M_L_CPU0_SB_DQ<22>
  VSS120  = GND
  DQ23_B  = M_L_CPU0_SB_DQ<23>
  VSS121  = GND
  DQ26_B  = M_L_CPU0_SB_DQ<26>
  VSS122  = GND
  DQ27_B  = M_L_CPU0_SB_DQ<27>
  VSS123  = GND
  \dqs8_b_c||tdqs8_b_c\  = M_L_CPU0_SB_DQS_DN<8>
  \dqs8_b_t||tdqs8_b_t\  = M_L_CPU0_SB_DQS_DP<8>
  VSS124  = GND
  DQ30_B  = M_L_CPU0_SB_DQ<30>
  VSS125  = GND
  DQ31_B  = M_L_CPU0_SB_DQ<31>
  VSS126  = GND
  G1  = GND
  G2  = GND
  G3  = GND

(kicad_pcb
	(version 20260206)
	(generator "pcbnew")
	(generator_version "10.0")
	(general
		(thickness 1.6)
		(legacy_teardrops no)
	)
	(paper "A4")
	(title_block
		(title "04192023_DAF0TMB3IC0_F0TG_MB_C_brd_V02_OCP.brd")
		(comment 1 "Grand Teton / footprint 3721 of 8354 (J67), pads 47-92 of 291")
	)
	(layers
		(0 "F.Cu" signal "TOP")
		(4 "In1.Cu" signal "GND")
		(6 "In2.Cu" signal "IN1")
		(8 "In3.Cu" signal "GND1")
		(10 "In4.Cu" signal "IN2")
		(12 "In5.Cu" signal "GND2")
		(14 "In6.Cu" signal "IN3")
		(16 "In7.Cu" signal "GND3")
		(18 "In8.Cu" signal "VCC")
		(20 "In9.Cu" signal "VCC1")
		(22 "In10.Cu" signal "GND4")
		(24 "In11.Cu" signal "IN4")
		(26 "In12.Cu" signal "GND5")
		(28 "In13.Cu" signal "IN5")
		(30 "In14.Cu" signal "GND6")
		(32 "In15.Cu" signal "IN6")
		(34 "In16.Cu" signal "GND7")
		(2 "B.Cu" signal "BOTTOM")
		(9 "F.Adhes" user "F.Adhesive")
		(11 "B.Adhes" user "B.Adhesive")
		(13 "F.Paste" user "Package Geometry/Pastemask Top")
		(15 "B.Paste" user "Package Geometry/Pastemask Bottom")
		(5 "F.SilkS" user "Ref Des/Silkscreen Top")
		(7 "B.SilkS" user "Ref Des/Silkscreen Bottom")
		(1 "F.Mask" user "Board Geometry/Soldermask Top")
		(3 "B.Mask" user "Board Geometry/Soldermask Bottom")
		(17 "Dwgs.User" user "User.Drawings")
		(19 "Cmts.User" user "User.Comments")
		(21 "Eco1.User" user "User.Eco1")
		(23 "Eco2.User" user "User.Eco2")
		(25 "Edge.Cuts" user "Board Geometry/Outline")
		(27 "Margin" user)
		(31 "F.CrtYd" user "Package Geometry/Place Bound Top")
		(29 "B.CrtYd" user "Package Geometry/Place Bound Bottom")
		(35 "F.Fab" user "Ref Des/Assembly Top")
		(33 "B.Fab" user "Ref Des/Assembly Bottom")
	)
	(footprint ""
		(layer "F.Cu")
		(at 452.138034 -255.560068 180)
		(property "Reference" "J67"
			(at 2.380488 -81.709768 0)
			(unlocked yes)
			(layer "F.SilkS")
			(effects
				(font
					(size 0.7874 0.5842)
					(thickness 0.1524)
				)
			)
		)
		(property "Value" ""
			(at 0 0 180)
			(layer "F.Fab")
			(effects
				(font
					(size 1.27 1.27)
				)
			)
		)
		(duplicate_pad_numbers_are_jumpers no)
		(pad "47" smd rect
			(at -2.050034 -24.224996 90)
			(size 0.519938 1.4986)
			(layers "F.Cu" "F.Mask" "F.Paste")
			(net "M_L_CPU0_SA_DQ<28>")
		)
		(pad "48" smd rect
			(at -2.050034 -23.375112 90)
			(size 0.519938 1.4986)
			(layers "F.Cu" "F.Mask" "F.Paste")
			(net "GND")
		)
		(pad "49" smd rect
			(at -2.050034 -22.524974 90)
			(size 0.519938 1.4986)
			(layers "F.Cu" "F.Mask" "F.Paste")
			(net "M_L_CPU0_SA_DQ<29>")
		)
		(pad "50" smd rect
			(at -2.050034 -21.67509 90)
			(size 0.519938 1.4986)
			(layers "F.Cu" "F.Mask" "F.Paste")
			(net "GND")
		)
		(pad "51" smd rect
			(at -2.050034 -20.824952 90)
			(size 0.519938 1.4986)
			(layers "F.Cu" "F.Mask" "F.Paste")
			(net "M_L_CPU0_SA_CB<0>")
		)
		(pad "52" smd rect
			(at -2.050034 -19.975068 90)
			(size 0.519938 1.4986)
			(layers "F.Cu" "F.Mask" "F.Paste")
			(net "GND")
		)
		(pad "53" smd rect
			(at -2.050034 -19.12493 90)
			(size 0.519938 1.4986)
			(layers "F.Cu" "F.Mask" "F.Paste")
			(net "M_L_CPU0_SA_CB<1>")
		)
		(pad "54" smd rect
			(at -2.050034 -18.275046 90)
			(size 0.519938 1.4986)
			(layers "F.Cu" "F.Mask" "F.Paste")
			(net "GND")
		)
		(pad "55" smd rect
			(at -2.050034 -17.424908 90)
			(size 0.519938 1.4986)
			(layers "F.Cu" "F.Mask" "F.Paste")
			(net "M_L_CPU0_SA_DQS_DP<4>")
		)
		(pad "56" smd rect
			(at -2.050034 -16.575024 90)
			(size 0.519938 1.4986)
			(layers "F.Cu" "F.Mask" "F.Paste")
			(net "M_L_CPU0_SA_DQS_DN<4>")
		)
		(pad "57" smd rect
			(at -2.050034 -15.724886 90)
			(size 0.519938 1.4986)
			(layers "F.Cu" "F.Mask" "F.Paste")
			(net "GND")
		)
		(pad "58" smd rect
			(at -2.050034 -14.875002 90)
			(size 0.519938 1.4986)
			(layers "F.Cu" "F.Mask" "F.Paste")
			(net "M_L_CPU0_SA_CB<4>")
		)
		(pad "59" smd rect
			(at -2.050034 -14.025118 90)
			(size 0.519938 1.4986)
			(layers "F.Cu" "F.Mask" "F.Paste")
			(net "GND")
		)
		(pad "60" smd rect
			(at -2.050034 -13.17498 90)
			(size 0.519938 1.4986)
			(layers "F.Cu" "F.Mask" "F.Paste")
			(net "M_L_CPU0_SA_CB<5>")
		)
		(pad "61" smd rect
			(at -2.050034 -12.325096 90)
			(size 0.519938 1.4986)
			(layers "F.Cu" "F.Mask" "F.Paste")
			(net "GND")
		)
		(pad "62" smd rect
			(at -2.050034 -11.474958 90)
			(size 0.519938 1.4986)
			(layers "F.Cu" "F.Mask" "F.Paste")
			(net "M_L_CPU0_ALERT_N")
		)
		(pad "63" smd rect
			(at -2.050034 -10.625074 90)
			(size 0.519938 1.4986)
			(layers "F.Cu" "F.Mask" "F.Paste")
			(net "GND")
		)
		(pad "64" smd rect
			(at -2.050034 -9.774936 90)
			(size 0.519938 1.4986)
			(layers "F.Cu" "F.Mask" "F.Paste")
			(net "M_L_CPU0_SA_CS_N<0>")
		)
		(pad "65" smd rect
			(at -2.050034 -8.925052 90)
			(size 0.519938 1.4986)
			(layers "F.Cu" "F.Mask" "F.Paste")
			(net "GND")
		)
		(pad "66" smd rect
			(at -2.050034 -8.074914 90)
			(size 0.519938 1.4986)
			(layers "F.Cu" "F.Mask" "F.Paste")
			(net "M_L_CPU0_SA_CA<0>")
		)
		(pad "67" smd rect
			(at -2.050034 -7.22503 90)
			(size 0.519938 1.4986)
			(layers "F.Cu" "F.Mask" "F.Paste")
			(net "GND")
		)
		(pad "68" smd rect
			(at -2.050034 -6.374892 90)
			(size 0.519938 1.4986)
			(layers "F.Cu" "F.Mask" "F.Paste")
			(net "M_L_CPU0_SA_CA<2>")
		)
		(pad "69" smd rect
			(at -2.050034 -5.525008 90)
			(size 0.519938 1.4986)
			(layers "F.Cu" "F.Mask" "F.Paste")
			(net "GND")
		)
		(pad "70" smd rect
			(at -2.050034 -4.675124 90)
			(size 0.519938 1.4986)
			(layers "F.Cu" "F.Mask" "F.Paste")
			(net "M_L_CPU0_SA_CA<4>")
		)
		(pad "71" smd rect
			(at -2.050034 -3.824986 90)
			(size 0.519938 1.4986)
			(layers "F.Cu" "F.Mask" "F.Paste")
			(net "GND")
		)
		(pad "72" smd rect
			(at -2.050034 -2.975102 90)
			(size 0.519938 1.4986)
			(layers "F.Cu" "F.Mask" "F.Paste")
			(net "M_L_CPU0_SA_CA<6>")
		)
		(pad "73" smd rect
			(at -2.050034 -2.124964 90)
			(size 0.519938 1.4986)
			(layers "F.Cu" "F.Mask" "F.Paste")
			(net "GND")
		)
		(pad "74" smd rect
			(at -2.050034 -1.27508 90)
			(size 0.519938 1.4986)
			(layers "F.Cu" "F.Mask" "F.Paste")
			(net "M_L_CPU0_SA_PAR")
		)
		(pad "75" smd rect
			(at -2.050034 -0.424942 90)
			(size 0.519938 1.4986)
			(layers "F.Cu" "F.Mask" "F.Paste")
			(net "GND")
		)
		(pad "76" smd rect
			(at -2.050034 5.525008 90)
			(size 0.519938 1.4986)
			(layers "F.Cu" "F.Mask" "F.Paste")
			(net "M_L_CPU0_SB_CA<0>")
		)
		(pad "77" smd rect
			(at -2.050034 6.374892 90)
			(size 0.519938 1.4986)
			(layers "F.Cu" "F.Mask" "F.Paste")
			(net "GND")
		)
		(pad "78" smd rect
			(at -2.050034 7.22503 90)
			(size 0.519938 1.4986)
			(layers "F.Cu" "F.Mask" "F.Paste")
			(net "M_L_CPU0_SB_CA<2>")
		)
		(pad "79" smd rect
			(at -2.050034 8.074914 90)
			(size 0.519938 1.4986)
			(layers "F.Cu" "F.Mask" "F.Paste")
			(net "GND")
		)
		(pad "80" smd rect
			(at -2.050034 8.925052 90)
			(size 0.519938 1.4986)
			(layers "F.Cu" "F.Mask" "F.Paste")
			(net "M_L_CPU0_SB_CA<4>")
		)
		(pad "81" smd rect
			(at -2.050034 9.774936 90)
			(size 0.519938 1.4986)
			(layers "F.Cu" "F.Mask" "F.Paste")
			(net "GND")
		)
		(pad "82" smd rect
			(at -2.050034 10.625074 90)
			(size 0.519938 1.4986)
			(layers "F.Cu" "F.Mask" "F.Paste")
			(net "M_L_CPU0_SB_CA<6>")
		)
		(pad "83" smd rect
			(at -2.050034 11.474958 90)
			(size 0.519938 1.4986)
			(layers "F.Cu" "F.Mask" "F.Paste")
			(net "GND")
		)
		(pad "84" smd rect
			(at -2.050034 12.325096 90)
			(size 0.519938 1.4986)
			(layers "F.Cu" "F.Mask" "F.Paste")
			(net "M_L_CPU0_SB_CS_N<0>")
		)
		(pad "85" smd rect
			(at -2.050034 13.17498 90)
			(size 0.519938 1.4986)
			(layers "F.Cu" "F.Mask" "F.Paste")
			(net "GND")
		)
		(pad "86" smd rect
			(at -2.050034 14.025118 90)
			(size 0.519938 1.4986)
			(layers "F.Cu" "F.Mask" "F.Paste")
			(net "M_L_CPU0_SA_RSP<0>")
		)
		(pad "87" smd rect
			(at -2.050034 14.875002 90)
			(size 0.519938 1.4986)
			(layers "F.Cu" "F.Mask" "F.Paste")
			(net "M_L_CPU0_SB_RSP<0>")
		)
		(pad "88" smd rect
			(at -2.050034 15.724886 90)
			(size 0.519938 1.4986)
			(layers "F.Cu" "F.Mask" "F.Paste")
			(net "GND")
		)
		(pad "89" smd rect
			(at -2.050034 16.575024 90)
			(size 0.519938 1.4986)
			(layers "F.Cu" "F.Mask" "F.Paste")
			(net "M_L_CPU0_SB_CB<4>")
		)
		(pad "90" smd rect
			(at -2.050034 17.424908 90)
			(size 0.519938 1.4986)
			(layers "F.Cu" "F.Mask" "F.Paste")
			(net "GND")
		)
		(pad "91" smd rect
			(at -2.050034 18.275046 90)
			(size 0.519938 1.4986)
			(layers "F.Cu" "F.Mask" "F.Paste")
			(net "M_L_CPU0_SB_CB<5>")
		)
		(pad "92" smd rect
			(at -2.050034 19.12493 90)
			(size 0.519938 1.4986)
			(layers "F.Cu" "F.Mask" "F.Paste")
			(net "GND")
		)
	)
)
